# BASEBOARD_FAB2 (Tioga Pass) — schematic netlist excerpt (pin names and nets, part order shuffled) for the footprints in the layout excerpt that follows; sources: Cadence DE-HDL packaged netlist, KiCad conversion of Wiwynn_Tioga_Pass_MB.brd

SH8U1  SHUNT  EMPTY  pkg SH0201  page 229 : A = VR_PVTT_GHJ_SNS ; B = PVTT_GHJ
C6P21  CAP_A  22.0UF 4V 20% X6S  pkg 0603V  page 203 : A = PVCCIN_CPU0 ; B = GND
C5P18  CAP  100UF 4V 20% X5R  pkg 0805  page 42 : A = PVCCMCP_CPU0 ; B = GND

(kicad_pcb
	(version 20260206)
	(generator "pcbnew")
	(generator_version "10.0")
	(general
		(thickness 1.6)
		(legacy_teardrops no)
	)
	(paper "A4")
	(title_block
		(title "Wiwynn_Tioga_Pass_MB.brd")
		(comment 1 "Tioga Pass / footprints 4696-4699 of 4770")
	)
	(layers
		(0 "F.Cu" signal "TOP")
		(4 "In1.Cu" signal "L2GND")
		(6 "In2.Cu" signal "L3")
		(8 "In3.Cu" signal "L4GND")
		(10 "In4.Cu" signal "L5")
		(12 "In5.Cu" signal "L6GND")
		(14 "In6.Cu" signal "L7VCC")
		(16 "In7.Cu" signal "L8VCC")
		(18 "In8.Cu" signal "L9GND")
		(20 "In9.Cu" signal "L10")
		(22 "In10.Cu" signal "L11GND")
		(24 "In11.Cu" signal "L12")
		(26 "In12.Cu" signal "L13GND")
		(2 "B.Cu" signal "BOTTOM")
		(9 "F.Adhes" user "F.Adhesive")
		(11 "B.Adhes" user "B.Adhesive")
		(13 "F.Paste" user "Package Geometry/Pastemask Top")
		(15 "B.Paste" user "Package Geometry/Pastemask Bottom")
		(5 "F.SilkS" user "Ref Des/Silkscreen Top")
		(7 "B.SilkS" user "Ref Des/Silkscreen Bottom")
		(1 "F.Mask" user "Board Geometry/Soldermask Top")
		(3 "B.Mask" user "Board Geometry/Soldermask Bottom")
		(17 "Dwgs.User" user "User.Drawings")
		(19 "Cmts.User" user "User.Comments")
		(21 "Eco1.User" user "User.Eco1")
		(23 "Eco2.User" user "User.Eco2")
		(25 "Edge.Cuts" user "Board Geometry/Outline")
		(27 "Margin" user)
		(31 "F.CrtYd" user "Package Geometry/Place Bound Top")
		(29 "B.CrtYd" user "Package Geometry/Place Bound Bottom")
		(35 "F.Fab" user "Ref Des/Assembly Top")
		(33 "B.Fab" user "Ref Des/Assembly Bottom")
	)
	(footprint ""
		(layer "B.Cu")
		(at 95.400368 3.4798 90)
		(property "Reference" "SH8U1"
			(at 0 0 90)
			(layer "B.SilkS")
			(hide yes)
			(effects
				(font
					(size 1.27 1.27)
				)
				(justify mirror)
			)
		)
		(property "Value" ""
			(at 0 0 90)
			(layer "B.Fab")
			(effects
				(font
					(size 1.27 1.27)
				)
				(justify mirror)
			)
		)
		(duplicate_pad_numbers_are_jumpers no)
		(fp_poly
			(pts
				(xy 0.1651 -0.0508) (xy 0.1651 0.5842) (xy -0.1651 0.5842) (xy -0.1651 -0.0508)
			)
			(stroke
				(width 0)
				(type default)
			)
			(fill no)
			(layer "B.CrtYd")
		)
		(fp_line
			(start 0.1651 -0.0508)
			(end -0.1651 -0.0508)
			(stroke
				(width 0.1)
				(type default)
			)
			(layer "B.Fab")
		)
		(fp_line
			(start -0.1651 -0.0508)
			(end -0.1651 0.5842)
			(stroke
				(width 0.1)
				(type default)
			)
			(layer "B.Fab")
		)
		(fp_line
			(start 0.1651 0.5842)
			(end 0.1651 -0.0508)
			(stroke
				(width 0.1)
				(type default)
			)
			(layer "B.Fab")
		)
		(fp_line
			(start -0.1651 0.5842)
			(end 0.1651 0.5842)
			(stroke
				(width 0.1)
				(type default)
			)
			(layer "B.Fab")
		)
		(pad "1" smd custom
			(at 0 0 90)
			(size 0.0762 0.0762)
			(layers "B.Cu" "B.Mask" "B.Paste")
			(net "VR_PVTT_GHJ_SNS")
			(options
				(clearance outline)
				(anchor circle)
			)
			(primitives
				(gr_poly
					(pts
						(arc
							(start -0.1524 0.10795)
							(mid -0.098518 0.130268)
							(end -0.0762 0.18415)
						)
						(xy -0.0762 0.22225) (xy 0.0762 0.22225)
						(arc
							(start 0.0762 0.18415)
							(mid 0.098518 0.130268)
							(end 0.1524 0.10795)
						)
						(xy 0.1524 -0.22225) (xy -0.1524 -0.22225)
					)
					(width 0)
					(fill yes)
				)
			)
		)
		(pad "2" smd custom
			(at 0 0.5334 270)
			(size 0.0762 0.0762)
			(layers "B.Cu" "B.Mask" "B.Paste")
			(net "PVTT_GHJ")
			(options
				(clearance outline)
				(anchor circle)
			)
			(primitives
				(gr_poly
					(pts
						(arc
							(start -0.1524 0.10795)
							(mid -0.098518 0.130268)
							(end -0.0762 0.18415)
						)
						(xy -0.0762 0.22225) (xy 0.0762 0.22225)
						(arc
							(start 0.0762 0.18415)
							(mid 0.098518 0.130268)
							(end 0.1524 0.10795)
						)
						(xy 0.1524 -0.22225) (xy -0.1524 -0.22225)
					)
					(width 0)
					(fill yes)
				)
			)
		)
	)
	(footprint ""
		(layer "B.Cu")
		(at 137.033 -121.412)
		(property "Reference" ""
			(at 0 0 0)
			(layer "B.SilkS")
			(hide yes)
			(effects
				(font
					(size 1.27 1.27)
				)
				(justify mirror)
			)
		)
		(property "Value" ""
			(at 0 0 0)
			(layer "B.Fab")
			(effects
				(font
					(size 1.27 1.27)
				)
				(justify mirror)
			)
		)
		(duplicate_pad_numbers_are_jumpers no)
		(fp_poly
			(pts
				(arc
					(start 2.032 0)
					(mid -2.032 0)
					(end 2.032 0)
				)
			)
			(stroke
				(width 0)
				(type default)
			)
			(fill no)
			(layer "B.CrtYd")
		)
		(pad "1" smd circle
			(at 0 0 180)
			(size 1.016 1.016)
			(layers "B.Cu" "B.Mask" "B.Paste")
			(net "Net_390")
		)
		(zone
			(layers "F.Cu" "B.Cu" "In1.Cu" "In2.Cu" "In3.Cu" "In4.Cu" "In5.Cu" "In6.Cu"
				"In7.Cu" "In8.Cu" "In9.Cu" "In10.Cu" "In11.Cu" "In12.Cu"
			)
			(hatch none 0.5)
			(connect_pads
				(clearance 0)
			)
			(min_thickness 0.25)
			(keepout
				(tracks allowed)
				(vias not_allowed)
				(pads allowed)
				(copperpour not_allowed)
				(footprints allowed)
			)
			(placement
				(enabled no)
				(sheetname "")
			)
			(fill
				(thermal_gap 0.5)
				(thermal_bridge_width 0.5)
				(island_removal_mode 0)
			)
			(polygon
				(pts
					(arc
						(start 138.557 -121.412)
						(mid 135.509 -121.412)
						(end 138.557 -121.412)
					)
				)
			)
		)
		(zone
			(layer "B.Cu")
			(hatch none 0.5)
			(connect_pads
				(clearance 0)
			)
			(min_thickness 0.25)
			(keepout
				(tracks not_allowed)
				(vias allowed)
				(pads allowed)
				(copperpour not_allowed)
				(footprints allowed)
			)
			(placement
				(enabled no)
				(sheetname "")
			)
			(fill
				(thermal_gap 0.5)
				(thermal_bridge_width 0.5)
				(island_removal_mode 0)
			)
			(polygon
				(pts
					(arc
						(start 138.557 -121.412)
						(mid 135.509 -121.412)
						(end 138.557 -121.412)
					)
				)
			)
		)
	)
	(footprint ""
		(layer "B.Cu")
		(at 275.008086 -77.82814)
		(property "Reference" "C5P18"
			(at 0 0 0)
			(layer "B.SilkS")
			(hide yes)
			(effects
				(font
					(size 1.27 1.27)
				)
				(justify mirror)
			)
		)
		(property "Value" ""
			(at 0 0 0)
			(layer "B.Fab")
			(effects
				(font
					(size 1.27 1.27)
				)
				(justify mirror)
			)
		)
		(duplicate_pad_numbers_are_jumpers no)
		(fp_poly
			(pts
				(xy 0.7239 -0.2159) (xy -0.7239 -0.2159) (xy -0.7239 1.9939) (xy 0.7239 1.9939)
			)
			(stroke
				(width 0)
				(type default)
			)
			(fill no)
			(layer "B.CrtYd")
		)
		(fp_line
			(start -0.7239 -0.2159)
			(end 0.7239 -0.2159)
			(stroke
				(width 0.1)
				(type default)
			)
			(layer "B.Fab")
		)
		(fp_line
			(start -0.7239 1.9939)
			(end -0.7239 -0.2159)
			(stroke
				(width 0.1)
				(type default)
			)
			(layer "B.Fab")
		)
		(fp_line
			(start 0.7239 -0.2159)
			(end 0.7239 1.9939)
			(stroke
				(width 0.1)
				(type default)
			)
			(layer "B.Fab")
		)
		(fp_line
			(start 0.7239 1.9939)
			(end -0.7239 1.9939)
			(stroke
				(width 0.1)
				(type default)
			)
			(layer "B.Fab")
		)
		(pad "1" smd rect
			(at 0 0 180)
			(size 1.27 1.016)
			(layers "B.Cu" "B.Mask" "B.Paste")
			(net "PVCCMCP_CPU0")
		)
		(pad "2" smd rect
			(at 0 1.778 180)
			(size 1.27 1.016)
			(layers "B.Cu" "B.Mask" "B.Paste")
			(net "GND")
		)
		(zone
			(layer "B.Cu")
			(hatch none 0.5)
			(connect_pads
				(clearance 0)
			)
			(min_thickness 0.25)
			(keepout
				(tracks not_allowed)
				(vias allowed)
				(pads allowed)
				(copperpour not_allowed)
				(footprints allowed)
			)
			(placement
				(enabled no)
				(sheetname "")
			)
			(fill
				(thermal_gap 0.5)
				(thermal_bridge_width 0.5)
				(island_removal_mode 0)
			)
			(polygon
				(pts
					(xy 275.643086 -77.32014) (xy 274.373086 -77.32014) (xy 274.373086 -76.55814) (xy 275.643086 -76.55814)
				)
			)
		)
	)
	(footprint ""
		(layer "B.Cu")
		(at 214.503 -70.358)
		(property "Reference" "C6P21"
			(at 0 0 0)
			(layer "B.SilkS")
			(hide yes)
			(effects
				(font
					(size 1.27 1.27)
				)
				(justify mirror)
			)
		)
		(property "Value" ""
			(at 0 0 0)
			(layer "B.Fab")
			(effects
				(font
					(size 1.27 1.27)
				)
				(justify mirror)
			)
		)
		(duplicate_pad_numbers_are_jumpers no)
		(fp_poly
			(pts
				(xy 0.4953 -0.2032) (xy -0.4953 -0.2032) (xy -0.4953 1.6002) (xy 0.4953 1.6002)
			)
			(stroke
				(width 0)
				(type default)
			)
			(fill no)
			(layer "B.CrtYd")
		)
		(fp_line
			(start -0.4953 -0.2032)
			(end -0.4953 1.6002)
			(stroke
				(width 0.1)
				(type default)
			)
			(layer "B.Fab")
		)
		(fp_line
			(start -0.4953 1.6002)
			(end 0.4953 1.6002)
			(stroke
				(width 0.1)
				(type default)
			)
			(layer "B.Fab")
		)
		(fp_line
			(start 0.4953 -0.2032)
			(end -0.4953 -0.2032)
			(stroke
				(width 0.1)
				(type default)
			)
			(layer "B.Fab")
		)
		(fp_line
			(start 0.4953 1.6002)
			(end 0.4953 -0.2032)
			(stroke
				(width 0.1)
				(type default)
			)
			(layer "B.Fab")
		)
		(pad "1" smd rect
			(at 0 0 180)
			(size 0.762 0.889)
			(layers "B.Cu" "B.Mask" "B.Paste")
			(net "PVCCIN_CPU0")
		)
		(pad "2" smd rect
			(at 0 1.397 180)
			(size 0.762 0.889)
			(layers "B.Cu" "B.Mask" "B.Paste")
			(net "GND")
		)
		(zone
			(layer "B.Cu")
			(hatch none 0.5)
			(connect_pads
				(clearance 0)
			)
			(min_thickness 0.25)
			(keepout
				(tracks not_allowed)
				(vias allowed)
				(pads allowed)
				(copperpour not_allowed)
				(footprints allowed)
			)
			(placement
				(enabled no)
				(sheetname "")
			)
			(fill
				(thermal_gap 0.5)
				(thermal_bridge_width 0.5)
				(island_removal_mode 0)
			)
			(polygon
				(pts
					(xy 214.884 -69.9135) (xy 214.122 -69.9135) (xy 214.122 -69.4055) (xy 214.884 -69.4055)
				)
			)
		)
	)
)
